(kicad_pcb
	(version 20241229)
	(generator "pcbnew")
	(generator_version "9.0")
	(general
		(thickness 1.552)
		(legacy_teardrops no)
	)
	(paper "A4")
	(title_block
		(date "2023-07-25")
		(rev "1.1.4")
		(comment 9 "footprints 58-61 of 379")
	)
	(layers
		(0 "F.Cu" signal)
		(4 "In1.Cu" signal)
		(6 "In2.Cu" signal)
		(8 "In3.Cu" signal)
		(10 "In4.Cu" signal)
		(12 "In5.Cu" signal)
		(14 "In6.Cu" signal)
		(2 "B.Cu" signal)
		(9 "F.Adhes" user "F.Adhesive")
		(11 "B.Adhes" user "B.Adhesive")
		(13 "F.Paste" user)
		(15 "B.Paste" user)
		(5 "F.SilkS" user "F.Silkscreen")
		(7 "B.SilkS" user "B.Silkscreen")
		(1 "F.Mask" user)
		(3 "B.Mask" user)
		(17 "Dwgs.User" user "User.Drawings")
		(19 "Cmts.User" user "User.Comments")
		(21 "Eco1.User" user "User.Eco1")
		(23 "Eco2.User" user "User.Eco2")
		(25 "Edge.Cuts" user)
		(27 "Margin" user)
		(31 "F.CrtYd" user "F.Courtyard")
		(29 "B.CrtYd" user "B.Courtyard")
		(35 "F.Fab" user)
		(33 "B.Fab" user)
	)
	(footprint "antmicro-footprints:R_1206_3216Metric"
		(layer "F.Cu")
		(at 154.79 70.65 -90)
		(property "Reference" "R13"
			(at 1.89 -2.04 270)
			(layer "F.SilkS")
			(effects
				(font
					(size 0.65 0.65)
					(thickness 0.15)
				)
				(justify left bottom)
			)
		)
		(property "Value" "R_0R_1206"
			(at 0 2 270)
			(layer "F.Fab")
			(hide yes)
			(effects
				(font
					(size 0.7 0.7)
					(thickness 0.15)
				)
				(justify left bottom)
			)
		)
		(property "Datasheet" "https://www.farnell.com/datasheets/2860635.pdf"
			(at 0 0 270)
			(layer "F.Fab")
			(hide yes)
			(effects
				(font
					(size 1.27 1.27)
					(thickness 0.15)
				)
			)
		)
		(property "Description" "Zero Ohm Resistor, Jumper, 1206 [3216 Metric], Thick Film, 250 mW, 2 A, Surface Mount Device"
			(at 0 0 270)
			(layer "F.Fab")
			(hide yes)
			(effects
				(font
					(size 1.27 1.27)
					(thickness 0.15)
				)
			)
		)
		(property "Author" "Antmicro"
			(at 84.14 225.44 0)
			(layer "F.Fab")
			(hide yes)
			(effects
				(font
					(size 1 1)
					(thickness 0.15)
				)
			)
		)
		(property "Current" "2A"
			(at 84.14 225.44 0)
			(layer "F.Fab")
			(hide yes)
			(effects
				(font
					(size 1 1)
					(thickness 0.15)
				)
			)
		)
		(property "License" "Apache-2.0"
			(at 84.14 225.44 0)
			(layer "F.Fab")
			(hide yes)
			(effects
				(font
					(size 1 1)
					(thickness 0.15)
				)
			)
		)
		(property "MPN" "MCMR12X000_PTL"
			(at 84.14 225.44 0)
			(layer "F.Fab")
			(hide yes)
			(effects
				(font
					(size 1 1)
					(thickness 0.15)
				)
			)
		)
		(property "Manufacturer" "Multicomp Pro"
			(at 84.14 225.44 0)
			(layer "F.Fab")
			(hide yes)
			(effects
				(font
					(size 1 1)
					(thickness 0.15)
				)
			)
		)
		(property "Tolerance" "~"
			(at 84.14 225.44 0)
			(layer "F.Fab")
			(hide yes)
			(effects
				(font
					(size 1 1)
					(thickness 0.15)
				)
			)
		)
		(property "Val" "0R"
			(at 84.14 225.44 0)
			(layer "F.Fab")
			(hide yes)
			(effects
				(font
					(size 1 1)
					(thickness 0.15)
				)
			)
		)
		(sheetname "/Power Supply/")
		(sheetfile "supply.kicad_sch")
		(attr smd)
		(fp_line
			(start 0.8 0.901)
			(end -0.8 0.901)
			(stroke
				(width 0.15)
				(type solid)
			)
			(layer "F.SilkS")
		)
		(fp_line
			(start 0.8 -0.899)
			(end -0.8 -0.899)
			(stroke
				(width 0.15)
				(type solid)
			)
			(layer "F.SilkS")
		)
		(fp_rect
			(start -2.325 -1.15)
			(end 2.325 1.15)
			(stroke
				(width 0.05)
				(type default)
			)
			(fill no)
			(layer "F.CrtYd")
		)
		(fp_line
			(start -1.601 0.8)
			(end 1.6 0.8)
			(stroke
				(width 0.15)
				(type solid)
			)
			(layer "F.Fab")
		)
		(fp_line
			(start -1.601 -0.802)
			(end -1.601 0.8)
			(stroke
				(width 0.15)
				(type solid)
			)
			(layer "F.Fab")
		)
		(fp_line
			(start -1.601 -0.802)
			(end 1.6 -0.802)
			(stroke
				(width 0.15)
				(type solid)
			)
			(layer "F.Fab")
		)
		(fp_line
			(start 1.6 -0.802)
			(end 1.6 0.8)
			(stroke
				(width 0.15)
				(type solid)
			)
			(layer "F.Fab")
		)
		(fp_text user "${REFERENCE}"
			(at -2.401 3.5 270)
			(layer "F.Fab")
			(effects
				(font
					(size 0.7 0.7)
					(thickness 0.15)
				)
				(justify left bottom)
			)
		)
		(fp_text user "Author: Antmicro"
			(at -2.401 4.899 270)
			(layer "F.Fab")
			(effects
				(font
					(size 0.7 0.7)
					(thickness 0.15)
				)
				(justify left bottom)
			)
		)
		(fp_text user "License: Apache-2.0"
			(at -2.401 6.3 270)
			(layer "F.Fab")
			(effects
				(font
					(size 0.7 0.7)
					(thickness 0.15)
				)
				(justify left bottom)
			)
		)
		(pad "1" smd roundrect
			(at -1.5 0.001 270)
			(size 1.15 1.8)
			(layers "F.Cu" "F.Mask" "F.Paste")
			(roundrect_rratio 0.25)
			(net 304 "/Power Supply/5V_I")
			(pintype "passive")
		)
		(pad "2" smd roundrect
			(at 1.5 0.001 270)
			(size 1.15 1.8)
			(layers "F.Cu" "F.Mask" "F.Paste")
			(roundrect_rratio 0.25)
			(net 14 "+5V")
			(pintype "passive")
		)
	)
	(footprint "antmicro-footprints:SOT-23-6"
		(layer "F.Cu")
		(at 161.4 91.1 -90)
		(property "Reference" "U13"
			(at -1.75 0.77 0)
			(layer "F.SilkS")
			(effects
				(font
					(size 0.65 0.65)
					(thickness 0.15)
				)
				(justify left bottom)
			)
		)
		(property "Value" "DIO7553ST6"
			(at -1.75 2.75 90)
			(layer "F.Fab")
			(hide yes)
			(effects
				(font
					(size 0.7 0.7)
					(thickness 0.15)
				)
				(justify right top)
			)
		)
		(property "Datasheet" "https://www.mouser.com/datasheet/2/802/7e5c577022fb784effcb3cdb25b437c0-1815562.pdf"
			(at 0 0 90)
			(layer "F.Fab")
			(hide yes)
			(effects
				(font
					(size 1.27 1.27)
					(thickness 0.15)
				)
			)
		)
		(property "Description" "Power switch"
			(at 0 0 90)
			(layer "F.Fab")
			(hide yes)
			(effects
				(font
					(size 1.27 1.27)
					(thickness 0.15)
				)
			)
		)
		(property "Author" "Antmicro"
			(at 70.3 252.5 0)
			(layer "F.Fab")
			(hide yes)
			(effects
				(font
					(size 1 1)
					(thickness 0.15)
				)
			)
		)
		(property "License" "Apache-2.0"
			(at 70.3 252.5 0)
			(layer "F.Fab")
			(hide yes)
			(effects
				(font
					(size 1 1)
					(thickness 0.15)
				)
			)
		)
		(property "MPN" "DIO7553ST6"
			(at 70.3 252.5 0)
			(layer "F.Fab")
			(hide yes)
			(effects
				(font
					(size 1 1)
					(thickness 0.15)
				)
			)
		)
		(property "Manufacturer" "DIOO Microcircuits"
			(at 70.3 252.5 0)
			(layer "F.Fab")
			(hide yes)
			(effects
				(font
					(size 1 1)
					(thickness 0.15)
				)
			)
		)
		(sheetname "/Peripherals/")
		(sheetfile "peripherals.kicad_sch")
		(attr smd)
		(fp_line
			(start -1.45 0.643)
			(end -1.45 0.343)
			(stroke
				(width 0.12)
				(type solid)
			)
			(layer "F.SilkS")
		)
		(fp_line
			(start 1.3 0.643)
			(end 1.45 0.643)
			(stroke
				(width 0.12)
				(type solid)
			)
			(layer "F.SilkS")
		)
		(fp_line
			(start 1.45 0.643)
			(end 1.45 0.343)
			(stroke
				(width 0.12)
				(type solid)
			)
			(layer "F.SilkS")
		)
		(fp_line
			(start -1.45 -0.757)
			(end -1.45 -0.457)
			(stroke
				(width 0.12)
				(type solid)
			)
			(layer "F.SilkS")
		)
		(fp_line
			(start -1.3 -0.757)
			(end -1.45 -0.757)
			(stroke
				(width 0.12)
				(type solid)
			)
			(layer "F.SilkS")
		)
		(fp_line
			(start 1.3 -0.757)
			(end 1.45 -0.757)
			(stroke
				(width 0.12)
				(type solid)
			)
			(layer "F.SilkS")
		)
		(fp_line
			(start 1.45 -0.757)
			(end 1.45 -0.457)
			(stroke
				(width 0.12)
				(type solid)
			)
			(layer "F.SilkS")
		)
		(fp_rect
			(start -1.55 -1.85)
			(end 1.55 1.75)
			(stroke
				(width 0.05)
				(type solid)
			)
			(fill no)
			(layer "F.CrtYd")
		)
		(fp_line
			(start -1.5 0.643)
			(end -1.5 -0.757)
			(stroke
				(width 0.1)
				(type solid)
			)
			(layer "F.Fab")
		)
		(fp_line
			(start 1.5 0.643)
			(end -1.5 0.643)
			(stroke
				(width 0.1)
				(type solid)
			)
			(layer "F.Fab")
		)
		(fp_line
			(start -1.5 -0.757)
			(end 1.5 -0.757)
			(stroke
				(width 0.1)
				(type solid)
			)
			(layer "F.Fab")
		)
		(fp_line
			(start 1.5 -0.757)
			(end 1.5 0.643)
			(stroke
				(width 0.1)
				(type solid)
			)
			(layer "F.Fab")
		)
		(fp_text user "."
			(at -1.48 1.5 90)
			(layer "F.SilkS")
			(effects
				(font
					(size 1 1)
					(thickness 0.15)
				)
			)
		)
		(fp_text user "License: Apache-2.0"
			(at -1.75 6.5 270)
			(layer "F.Fab")
			(effects
				(font
					(size 0.7 0.7)
					(thickness 0.15)
				)
				(justify left bottom)
			)
		)
		(fp_text user "Author: Antmicro"
			(at -1.829 5.25 270)
			(layer "F.Fab")
			(effects
				(font
					(size 0.7 0.7)
					(thickness 0.15)
				)
				(justify left bottom)
			)
		)
		(fp_text user "${REFERENCE}"
			(at -1.75 4 270)
			(layer "F.Fab")
			(effects
				(font
					(size 0.7 0.7)
					(thickness 0.15)
				)
				(justify left bottom)
			)
		)
		(pad "1" smd roundrect
			(at -0.954 1.1 270)
			(size 0.55 1)
			(layers "F.Cu" "F.Mask" "F.Paste")
			(roundrect_rratio 0.15)
			(net 2 "+3V3")
			(pinfunction "IN")
			(pintype "power_in")
		)
		(pad "2" smd roundrect
			(at -0.003 1.1 270)
			(size 0.55 1)
			(layers "F.Cu" "F.Mask" "F.Paste")
			(roundrect_rratio 0.15)
			(net 1 "GND")
			(pinfunction "GND")
			(pintype "power_in")
		)
		(pad "3" smd roundrect
			(at 0.947 1.1 270)
			(size 0.55 1)
			(layers "F.Cu" "F.Mask" "F.Paste")
			(roundrect_rratio 0.15)
			(net 307 "/Peripherals/FFC1_PEN")
			(pinfunction "EN")
			(pintype "input")
		)
		(pad "4" smd roundrect
			(at 0.947 -1.214 270)
			(size 0.55 1)
			(layers "F.Cu" "F.Mask" "F.Paste")
			(roundrect_rratio 0.15)
			(net 351 "Net-(U13-~{FAULT})")
			(pinfunction "~{FAULT}")
			(pintype "output")
		)
		(pad "5" smd roundrect
			(at -0.003 -1.214 270)
			(size 0.55 1)
			(layers "F.Cu" "F.Mask" "F.Paste")
			(roundrect_rratio 0.15)
			(net 353 "Net-(U13-ILIM)")
			(pinfunction "ILIM")
			(pintype "passive")
		)
		(pad "6" smd roundrect
			(at -0.954 -1.214 270)
			(size 0.55 1)
			(layers "F.Cu" "F.Mask" "F.Paste")
			(roundrect_rratio 0.15)
			(net 17 "/Peripherals/FFC1_3V3")
			(pinfunction "OUT")
			(pintype "power_out")
		)
	)
	(footprint "antmicro-footprints:R_0603_1608Metric"
		(layer "F.Cu")
		(at 108.75 70.55 90)
		(descr "Resistor SMD 0603")
		(tags "resistor SMD 0603")
		(property "Reference" "R101"
			(at 1.41 0.28 90)
			(layer "F.SilkS")
			(effects
				(font
					(size 0.65 0.65)
					(thickness 0.15)
				)
				(justify left bottom)
			)
		)
		(property "Value" "R_200R_0603"
			(at 0 1.6 90)
			(layer "F.Fab")
			(hide yes)
			(effects
				(font
					(size 0.7 0.7)
					(thickness 0.15)
				)
				(justify left bottom)
			)
		)
		(property "Datasheet" "https://www.bourns.com/docs/product-datasheets/cr.pdf"
			(at 0 0 90)
			(layer "F.Fab")
			(hide yes)
			(effects
				(font
					(size 1.27 1.27)
					(thickness 0.15)
				)
			)
		)
		(property "Description" "SMD Chip Resistor, 200 ohm, ± 1%, 100 mW, 0603 [1608 Metric], Thick Film, General Purpose"
			(at 0 0 90)
			(layer "F.Fab")
			(hide yes)
			(effects
				(font
					(size 1.27 1.27)
					(thickness 0.15)
				)
			)
		)
		(property "Author" "Antmicro"
			(at 179.3 -38.2 0)
			(layer "F.Fab")
			(hide yes)
			(effects
				(font
					(size 1 1)
					(thickness 0.15)
				)
			)
		)
		(property "License" "Apache-2.0"
			(at 179.3 -38.2 0)
			(layer "F.Fab")
			(hide yes)
			(effects
				(font
					(size 1 1)
					(thickness 0.15)
				)
			)
		)
		(property "MPN" "CR0603-FX-2000ELF"
			(at 179.3 -38.2 0)
			(layer "F.Fab")
			(hide yes)
			(effects
				(font
					(size 1 1)
					(thickness 0.15)
				)
			)
		)
		(property "Manufacturer" "Bourns"
			(at 179.3 -38.2 0)
			(layer "F.Fab")
			(hide yes)
			(effects
				(font
					(size 1 1)
					(thickness 0.15)
				)
			)
		)
		(property "Tolerance" "1%"
			(at 179.3 -38.2 0)
			(layer "F.Fab")
			(hide yes)
			(effects
				(font
					(size 1 1)
					(thickness 0.15)
				)
			)
		)
		(property "Val" "200R"
			(at 179.3 -38.2 0)
			(layer "F.Fab")
			(hide yes)
			(effects
				(font
					(size 1 1)
					(thickness 0.15)
				)
			)
		)
		(sheetname "/SDI/")
		(sheetfile "sdi.kicad_sch")
		(attr smd)
		(fp_line
			(start -0.15 -0.4)
			(end 0.15 -0.4)
			(stroke
				(width 0.15)
				(type solid)
			)
			(layer "F.SilkS")
		)
		(fp_line
			(start -0.15 0.4)
			(end 0.15 0.4)
			(stroke
				(width 0.15)
				(type solid)
			)
			(layer "F.SilkS")
		)
		(fp_rect
			(start -1.25 -0.65)
			(end 1.25 0.65)
			(stroke
				(width 0.05)
				(type solid)
			)
			(fill no)
			(layer "F.CrtYd")
		)
		(fp_rect
			(start -0.8 -0.4)
			(end 0.8 0.4)
			(stroke
				(width 0.15)
				(type solid)
			)
			(fill no)
			(layer "F.Fab")
		)
		(fp_text user "License: Apache-2.0"
			(at -1.25 5.9 90)
			(layer "F.Fab")
			(effects
				(font
					(size 0.7 0.7)
					(thickness 0.15)
				)
				(justify left bottom)
			)
		)
		(fp_text user "${REFERENCE}"
			(at -1.25 3.898 90)
			(layer "F.Fab")
			(effects
				(font
					(size 0.7 0.7)
					(thickness 0.15)
				)
				(justify left bottom)
			)
		)
		(fp_text user "Author: Antmicro"
			(at -1.25 4.9 90)
			(layer "F.Fab")
			(effects
				(font
					(size 0.7 0.7)
					(thickness 0.15)
				)
				(justify left bottom)
			)
		)
		(pad "1" smd roundrect
			(at -0.7 0 90)
			(size 0.8 1)
			(layers "F.Cu" "F.Mask" "F.Paste")
			(roundrect_rratio 0.2)
			(net 247 "Net-(D8-A)")
			(pintype "passive")
		)
		(pad "2" smd roundrect
			(at 0.7 0 90)
			(size 0.8 1)
			(layers "F.Cu" "F.Mask" "F.Paste")
			(roundrect_rratio 0.2)
			(net 219 "/SDI/SDI_STAT3")
			(pintype "passive")
		)
	)
	(footprint "antmicro-footprints:R_0402_1005Metric"
		(layer "F.Cu")
		(at 84.2 107.15 180)
		(descr "Resistor SMD 0402")
		(tags "resistor SMD 0402")
		(property "Reference" "R60"
			(at -4.33 7.91 0)
			(layer "F.SilkS")
			(effects
				(font
					(size 0.65 0.65)
					(thickness 0.15)
				)
				(justify right bottom)
			)
		)
		(property "Value" "R_75R_0402"
			(at 0 1.4 0)
			(layer "F.Fab")
			(hide yes)
			(effects
				(font
					(size 0.7 0.7)
					(thickness 0.15)
				)
				(justify right bottom)
			)
		)
		(property "Datasheet" "https://www.bourns.com/docs/product-datasheets/cr.pdf"
			(at 0 0 180)
			(layer "F.Fab")
			(hide yes)
			(effects
				(font
					(size 1.27 1.27)
					(thickness 0.15)
				)
			)
		)
		(property "Description" "SMD Chip Resistor, 75 ohm, ± 1%, 62.5 mW, 0402 [1005 Metric], Thick Film, General Purpose"
			(at 0 0 180)
			(layer "F.Fab")
			(hide yes)
			(effects
				(font
					(size 1.27 1.27)
					(thickness 0.15)
				)
			)
		)
		(property "Author" "Antmicro"
			(at 168.4 214.3 0)
			(layer "F.Fab")
			(hide yes)
			(effects
				(font
					(size 1 1)
					(thickness 0.15)
				)
			)
		)
		(property "License" "Apache-2.0"
			(at 168.4 214.3 0)
			(layer "F.Fab")
			(hide yes)
			(effects
				(font
					(size 1 1)
					(thickness 0.15)
				)
			)
		)
		(property "MPN" "CR0402-FX-75R0GLF"
			(at 168.4 214.3 0)
			(layer "F.Fab")
			(hide yes)
			(effects
				(font
					(size 1 1)
					(thickness 0.15)
				)
			)
		)
		(property "Manufacturer" "Bourns"
			(at 168.4 214.3 0)
			(layer "F.Fab")
			(hide yes)
			(effects
				(font
					(size 1 1)
					(thickness 0.15)
				)
			)
		)
		(property "Tolerance" "1%"
			(at 168.4 214.3 0)
			(layer "F.Fab")
			(hide yes)
			(effects
				(font
					(size 1 1)
					(thickness 0.15)
				)
			)
		)
		(property "Val" "75R"
			(at 168.4 214.3 0)
			(layer "F.Fab")
			(hide yes)
			(effects
				(font
					(size 1 1)
					(thickness 0.15)
				)
			)
		)
		(sheetname "/SDI/")
		(sheetfile "sdi.kicad_sch")
		(attr smd)
		(fp_rect
			(start -0.925 -0.47)
			(end 0.925 0.47)
			(stroke
				(width 0.05)
				(type default)
			)
			(fill no)
			(layer "F.CrtYd")
		)
		(fp_rect
			(start -0.5 -0.25)
			(end 0.5 0.25)
			(stroke
				(width 0.15)
				(type solid)
			)
			(fill no)
			(layer "F.Fab")
		)
		(fp_text user "Author: Antmicro"
			(at -0.95 4.169 180)
			(layer "F.Fab")
			(effects
				(font
					(size 0.7 0.7)
					(thickness 0.15)
				)
				(justify left bottom)
			)
		)
		(fp_text user "License: Apache-2.0"
			(at -0.95 5.169 180)
			(layer "F.Fab")
			(effects
				(font
					(size 0.7 0.7)
					(thickness 0.15)
				)
				(justify left bottom)
			)
		)
		(fp_text user "${REFERENCE}"
			(at -0.95 3.168 180)
			(layer "F.Fab")
			(effects
				(font
					(size 0.7 0.7)
					(thickness 0.15)
				)
				(justify left bottom)
			)
		)
		(pad "1" smd roundrect
			(at -0.48 0 180)
			(size 0.59 0.64)
			(layers "F.Cu" "F.Mask" "F.Paste")
			(roundrect_rratio 0.25)
			(net 249 "/SDI/SDI_OUT_P")
			(pintype "passive")
		)
		(pad "2" smd roundrect
			(at 0.48 0 180)
			(size 0.59 0.64)
			(layers "F.Cu" "F.Mask" "F.Paste")
			(roundrect_rratio 0.25)
			(net 2 "+3V3")
			(pintype "passive")
		)
	)
)
